# SCM (Grand Teton) — schematic netlist excerpt (pin names and nets, part order shuffled) for the footprints in the layout excerpt that follows; sources: Cadence DE-HDL packaged netlist, KiCad conversion of 12092022_DA0F0TMDCD0_F0T_Management_Board_D_brd_V3_OCP.brd

R861  Q_RES  22 1% CHIP  pkg 0402LF  page 44 : A = SPI_SYS_R_MISO ; B = SPI_SYS_MUX_MISO
R718  Q_RES  33.2 1% CHIP  pkg 0402LF  page 34 : A = RST_PLTRST_N ; B = RST_PLTRST_R1_N

(kicad_pcb
	(version 20260206)
	(generator "pcbnew")
	(generator_version "10.0")
	(general
		(thickness 1.6)
		(legacy_teardrops no)
	)
	(paper "A4")
	(title_block
		(title "12092022_DA0F0TMDCD0_F0T_Management_Board_D_brd_V3_OCP.brd")
		(comment 1 "Grand Teton / footprints 477-478 of 1440")
	)
	(layers
		(0 "F.Cu" signal "TOP")
		(4 "In1.Cu" signal "GND")
		(6 "In2.Cu" signal "IN1")
		(8 "In3.Cu" signal "GND1")
		(10 "In4.Cu" signal "IN2")
		(12 "In5.Cu" signal "VCC")
		(14 "In6.Cu" signal "VCC1")
		(16 "In7.Cu" signal "IN3")
		(18 "In8.Cu" signal "GND2")
		(20 "In9.Cu" signal "IN4")
		(22 "In10.Cu" signal "GND3")
		(2 "B.Cu" signal "BOTTOM")
		(9 "F.Adhes" user "F.Adhesive")
		(11 "B.Adhes" user "B.Adhesive")
		(13 "F.Paste" user "Package Geometry/Pastemask Top")
		(15 "B.Paste" user "Package Geometry/Pastemask Bottom")
		(5 "F.SilkS" user "Ref Des/Silkscreen Top")
		(7 "B.SilkS" user "Ref Des/Silkscreen Bottom")
		(1 "F.Mask" user "Board Geometry/Soldermask Top")
		(3 "B.Mask" user "Board Geometry/Soldermask Bottom")
		(17 "Dwgs.User" user "User.Drawings")
		(19 "Cmts.User" user "User.Comments")
		(21 "Eco1.User" user "User.Eco1")
		(23 "Eco2.User" user "User.Eco2")
		(25 "Edge.Cuts" user "Board Geometry/Outline")
		(27 "Margin" user)
		(31 "F.CrtYd" user "Package Geometry/Place Bound Top")
		(29 "B.CrtYd" user "Package Geometry/Place Bound Bottom")
		(35 "F.Fab" user "Ref Des/Assembly Top")
		(33 "B.Fab" user "Ref Des/Assembly Bottom")
	)
	(footprint ""
		(layer "F.Cu")
		(at 53.7718 -109.3978 -90)
		(property "Reference" "R861"
			(at 0 0 270)
			(layer "F.SilkS")
			(hide yes)
			(effects
				(font
					(size 1.27 1.27)
				)
			)
		)
		(property "Value" ""
			(at 0 0 270)
			(layer "F.Fab")
			(effects
				(font
					(size 1.27 1.27)
				)
			)
		)
		(duplicate_pad_numbers_are_jumpers no)
		(fp_line
			(start -0.7874 0.4064)
			(end -0.7874 -0.4064)
			(stroke
				(width 0.1524)
				(type default)
			)
			(layer "F.SilkS")
		)
		(fp_line
			(start 0.7874 0.4064)
			(end -0.7874 0.4064)
			(stroke
				(width 0.1524)
				(type default)
			)
			(layer "F.SilkS")
		)
		(fp_line
			(start -0.7874 -0.4064)
			(end 0.7874 -0.4064)
			(stroke
				(width 0.1524)
				(type default)
			)
			(layer "F.SilkS")
		)
		(fp_line
			(start 0.7874 -0.4064)
			(end 0.7874 0.4064)
			(stroke
				(width 0.1524)
				(type default)
			)
			(layer "F.SilkS")
		)
		(fp_line
			(start -0.67945 0.3048)
			(end -0.67945 -0.305054)
			(stroke
				(width 0.1)
				(type default)
			)
			(layer "F.Fab")
		)
		(fp_line
			(start -0.12065 0.3048)
			(end -0.67945 0.3048)
			(stroke
				(width 0.1)
				(type default)
			)
			(layer "F.Fab")
		)
		(fp_line
			(start 0.120396 0.3048)
			(end 0.120396 0.2794)
			(stroke
				(width 0.1)
				(type default)
			)
			(layer "F.Fab")
		)
		(fp_line
			(start 0.67945 0.3048)
			(end 0.120396 0.3048)
			(stroke
				(width 0.1)
				(type default)
			)
			(layer "F.Fab")
		)
		(fp_line
			(start -0.12065 0.2794)
			(end -0.12065 0.3048)
			(stroke
				(width 0.1)
				(type default)
			)
			(layer "F.Fab")
		)
		(fp_line
			(start 0.120396 0.2794)
			(end -0.12065 0.2794)
			(stroke
				(width 0.1)
				(type default)
			)
			(layer "F.Fab")
		)
		(fp_line
			(start -0.12065 -0.2794)
			(end 0.12065 -0.2794)
			(stroke
				(width 0.1)
				(type default)
			)
			(layer "F.Fab")
		)
		(fp_line
			(start 0.12065 -0.2794)
			(end 0.12065 -0.3048)
			(stroke
				(width 0.1)
				(type default)
			)
			(layer "F.Fab")
		)
		(fp_line
			(start 0.12065 -0.3048)
			(end 0.67945 -0.3048)
			(stroke
				(width 0.1)
				(type default)
			)
			(layer "F.Fab")
		)
		(fp_line
			(start 0.67945 -0.3048)
			(end 0.67945 0.3048)
			(stroke
				(width 0.1)
				(type default)
			)
			(layer "F.Fab")
		)
		(fp_line
			(start -0.67945 -0.305054)
			(end -0.12065 -0.305054)
			(stroke
				(width 0.1)
				(type default)
			)
			(layer "F.Fab")
		)
		(fp_line
			(start -0.12065 -0.305054)
			(end -0.12065 -0.2794)
			(stroke
				(width 0.1)
				(type default)
			)
			(layer "F.Fab")
		)
		(pad "1" smd circle
			(at -0.40005 0 270)
			(size 0 0)
			(layers "F.Cu" "F.Mask" "F.Paste")
			(net "SPI_SYS_R_MISO")
		)
		(pad "2" smd circle
			(at 0.40005 0 270)
			(size 0 0)
			(layers "F.Cu" "F.Mask" "F.Paste")
			(net "SPI_SYS_MUX_MISO")
		)
	)
	(footprint ""
		(layer "F.Cu")
		(at 30.5562 -86.995 180)
		(property "Reference" "R718"
			(at 0 0 180)
			(layer "F.SilkS")
			(hide yes)
			(effects
				(font
					(size 1.27 1.27)
				)
			)
		)
		(property "Value" ""
			(at 0 0 180)
			(layer "F.Fab")
			(effects
				(font
					(size 1.27 1.27)
				)
			)
		)
		(duplicate_pad_numbers_are_jumpers no)
		(fp_line
			(start 0.7874 0.4064)
			(end -0.7874 0.4064)
			(stroke
				(width 0.1524)
				(type default)
			)
			(layer "F.SilkS")
		)
		(fp_line
			(start 0.7874 -0.4064)
			(end 0.7874 0.4064)
			(stroke
				(width 0.1524)
				(type default)
			)
			(layer "F.SilkS")
		)
		(fp_line
			(start -0.7874 0.4064)
			(end -0.7874 -0.4064)
			(stroke
				(width 0.1524)
				(type default)
			)
			(layer "F.SilkS")
		)
		(fp_line
			(start -0.7874 -0.4064)
			(end 0.7874 -0.4064)
			(stroke
				(width 0.1524)
				(type default)
			)
			(layer "F.SilkS")
		)
		(fp_line
			(start 0.67945 0.3048)
			(end 0.120396 0.3048)
			(stroke
				(width 0.1)
				(type default)
			)
			(layer "F.Fab")
		)
		(fp_line
			(start 0.67945 -0.3048)
			(end 0.67945 0.3048)
			(stroke
				(width 0.1)
				(type default)
			)
			(layer "F.Fab")
		)
		(fp_line
			(start 0.12065 -0.2794)
			(end 0.12065 -0.3048)
			(stroke
				(width 0.1)
				(type default)
			)
			(layer "F.Fab")
		)
		(fp_line
			(start 0.12065 -0.3048)
			(end 0.67945 -0.3048)
			(stroke
				(width 0.1)
				(type default)
			)
			(layer "F.Fab")
		)
		(fp_line
			(start 0.120396 0.3048)
			(end 0.120396 0.2794)
			(stroke
				(width 0.1)
				(type default)
			)
			(layer "F.Fab")
		)
		(fp_line
			(start 0.120396 0.2794)
			(end -0.12065 0.2794)
			(stroke
				(width 0.1)
				(type default)
			)
			(layer "F.Fab")
		)
		(fp_line
			(start -0.12065 0.3048)
			(end -0.67945 0.3048)
			(stroke
				(width 0.1)
				(type default)
			)
			(layer "F.Fab")
		)
		(fp_line
			(start -0.12065 0.2794)
			(end -0.12065 0.3048)
			(stroke
				(width 0.1)
				(type default)
			)
			(layer "F.Fab")
		)
		(fp_line
			(start -0.12065 -0.2794)
			(end 0.12065 -0.2794)
			(stroke
				(width 0.1)
				(type default)
			)
			(layer "F.Fab")
		)
		(fp_line
			(start -0.12065 -0.305054)
			(end -0.12065 -0.2794)
			(stroke
				(width 0.1)
				(type default)
			)
			(layer "F.Fab")
		)
		(fp_line
			(start -0.67945 0.3048)
			(end -0.67945 -0.305054)
			(stroke
				(width 0.1)
				(type default)
			)
			(layer "F.Fab")
		)
		(fp_line
			(start -0.67945 -0.305054)
			(end -0.12065 -0.305054)
			(stroke
				(width 0.1)
				(type default)
			)
			(layer "F.Fab")
		)
		(pad "1" smd circle
			(at -0.40005 0 180)
			(size 0 0)
			(layers "F.Cu" "F.Mask" "F.Paste")
			(net "RST_PLTRST_N")
		)
		(pad "2" smd circle
			(at 0.40005 0 180)
			(size 0 0)
			(layers "F.Cu" "F.Mask" "F.Paste")
			(net "RST_PLTRST_R1_N")
		)
	)
)
